# T6G (Grand Teton) — schematic netlist excerpt (pin names and nets, part order shuffled) for the footprints in the layout excerpt that follows; sources: Cadence DE-HDL packaged netlist, KiCad conversion of 04192023_DAF0TMB3IC0_F0TG_MB_C_brd_V02_OCP.brd

PC381_1  Q_CAP  22UF 16V 20% X6S  pkg C0805  page 218 : A = SW_P12V_AUX_PVDDCR_CPU1_P1_FLT ; B = GND
R838  Q_RES  1K 1% CHIP  pkg 0201LF  page 185 : A = P1V8_CPU0_RT_1D ; B = SMB_RT_CPU0_P3_ROM_R_SDA
PC450  Q_CAPP  470UF 2.5V 20% SPCAP  pkg SMLF  page 222 : A = PVDDIO_P1 ; B = GND

(kicad_pcb
	(version 20260206)
	(generator "pcbnew")
	(generator_version "10.0")
	(general
		(thickness 1.6)
		(legacy_teardrops no)
	)
	(paper "A4")
	(title_block
		(title "04192023_DAF0TMB3IC0_F0TG_MB_C_brd_V02_OCP.brd")
		(comment 1 "Grand Teton / footprints 7278-7280 of 8354")
	)
	(layers
		(0 "F.Cu" signal "TOP")
		(4 "In1.Cu" signal "GND")
		(6 "In2.Cu" signal "IN1")
		(8 "In3.Cu" signal "GND1")
		(10 "In4.Cu" signal "IN2")
		(12 "In5.Cu" signal "GND2")
		(14 "In6.Cu" signal "IN3")
		(16 "In7.Cu" signal "GND3")
		(18 "In8.Cu" signal "VCC")
		(20 "In9.Cu" signal "VCC1")
		(22 "In10.Cu" signal "GND4")
		(24 "In11.Cu" signal "IN4")
		(26 "In12.Cu" signal "GND5")
		(28 "In13.Cu" signal "IN5")
		(30 "In14.Cu" signal "GND6")
		(32 "In15.Cu" signal "IN6")
		(34 "In16.Cu" signal "GND7")
		(2 "B.Cu" signal "BOTTOM")
		(9 "F.Adhes" user "F.Adhesive")
		(11 "B.Adhes" user "B.Adhesive")
		(13 "F.Paste" user "Package Geometry/Pastemask Top")
		(15 "B.Paste" user "Package Geometry/Pastemask Bottom")
		(5 "F.SilkS" user "Ref Des/Silkscreen Top")
		(7 "B.SilkS" user "Ref Des/Silkscreen Bottom")
		(1 "F.Mask" user "Board Geometry/Soldermask Top")
		(3 "B.Mask" user "Board Geometry/Soldermask Bottom")
		(17 "Dwgs.User" user "User.Drawings")
		(19 "Cmts.User" user "User.Comments")
		(21 "Eco1.User" user "User.Eco1")
		(23 "Eco2.User" user "User.Eco2")
		(25 "Edge.Cuts" user "Board Geometry/Outline")
		(27 "Margin" user)
		(31 "F.CrtYd" user "Package Geometry/Place Bound Top")
		(29 "B.CrtYd" user "Package Geometry/Place Bound Bottom")
		(35 "F.Fab" user "Ref Des/Assembly Top")
		(33 "B.Fab" user "Ref Des/Assembly Bottom")
	)
	(footprint ""
		(layer "B.Cu")
		(at 88.243918 -335.04632 90)
		(property "Reference" "PC381_1"
			(at 0 0 90)
			(layer "B.SilkS")
			(hide yes)
			(effects
				(font
					(size 1.27 1.27)
				)
				(justify mirror)
			)
		)
		(property "Value" ""
			(at 0 0 90)
			(layer "B.Fab")
			(effects
				(font
					(size 1.27 1.27)
				)
				(justify mirror)
			)
		)
		(duplicate_pad_numbers_are_jumpers no)
		(fp_line
			(start 1.524 -0.762)
			(end -1.524 -0.762)
			(stroke
				(width 0.1524)
				(type default)
			)
			(layer "B.SilkS")
		)
		(fp_line
			(start -1.524 -0.762)
			(end -1.524 0.762)
			(stroke
				(width 0.1524)
				(type default)
			)
			(layer "B.SilkS")
		)
		(fp_line
			(start 1.524 0.762)
			(end 1.524 -0.762)
			(stroke
				(width 0.1524)
				(type default)
			)
			(layer "B.SilkS")
		)
		(fp_line
			(start -1.524 0.762)
			(end 1.524 0.762)
			(stroke
				(width 0.1524)
				(type default)
			)
			(layer "B.SilkS")
		)
		(fp_line
			(start 1.1049 -0.724916)
			(end 1.1049 0.724916)
			(stroke
				(width 0.1)
				(type default)
			)
			(layer "B.Fab")
		)
		(fp_line
			(start -1.1049 -0.724916)
			(end 1.1049 -0.724916)
			(stroke
				(width 0.1)
				(type default)
			)
			(layer "B.Fab")
		)
		(fp_line
			(start 1.1049 0.724916)
			(end -1.1049 0.724916)
			(stroke
				(width 0.1)
				(type default)
			)
			(layer "B.Fab")
		)
		(fp_line
			(start -1.1049 0.724916)
			(end -1.1049 -0.724916)
			(stroke
				(width 0.1)
				(type default)
			)
			(layer "B.Fab")
		)
		(pad "1" smd rect
			(at 0.889 0 90)
			(size 1.016 1.27)
			(layers "B.Cu" "B.Mask" "B.Paste")
			(net "SW_P12V_AUX_PVDDCR_CPU1_P1_FLT")
		)
		(pad "2" smd rect
			(at -0.889 0 90)
			(size 1.016 1.27)
			(layers "B.Cu" "B.Mask" "B.Paste")
			(net "GND")
		)
	)
	(footprint ""
		(layer "B.Cu")
		(at 53.084476 -339.890354 -90)
		(property "Reference" "PC450"
			(at 9.660636 -0.954786 270)
			(unlocked yes)
			(layer "B.SilkS")
			(effects
				(font
					(size 0.7874 0.5842)
					(thickness 0.1524)
				)
				(justify left mirror)
			)
		)
		(property "Value" ""
			(at 0 0 90)
			(layer "B.Fab")
			(effects
				(font
					(size 1.27 1.27)
				)
				(justify mirror)
			)
		)
		(duplicate_pad_numbers_are_jumpers no)
		(fp_line
			(start -4.533392 2.249932)
			(end 4.533392 2.249932)
			(stroke
				(width 0.1524)
				(type default)
			)
			(layer "B.SilkS")
		)
		(fp_line
			(start 4.533392 2.249932)
			(end 4.533392 -2.249932)
			(stroke
				(width 0.1524)
				(type default)
			)
			(layer "B.SilkS")
		)
		(fp_line
			(start -4.533392 -2.249932)
			(end -4.533392 2.249932)
			(stroke
				(width 0.1524)
				(type default)
			)
			(layer "B.SilkS")
		)
		(fp_line
			(start 4.533392 -2.249932)
			(end -4.533392 -2.249932)
			(stroke
				(width 0.1524)
				(type default)
			)
			(layer "B.SilkS")
		)
		(fp_rect
			(start 5.39242 2.326132)
			(end 4.533392 -2.326132)
			(stroke
				(width 0)
				(type default)
			)
			(fill yes)
			(layer "B.SilkS")
		)
		(fp_line
			(start -3.750056 2.249932)
			(end 3.750056 2.249932)
			(stroke
				(width 0.1)
				(type default)
			)
			(layer "B.Fab")
		)
		(fp_line
			(start 3.750056 2.249932)
			(end 3.750056 -2.249932)
			(stroke
				(width 0.1)
				(type default)
			)
			(layer "B.Fab")
		)
		(fp_line
			(start -3.750056 -2.249932)
			(end -3.750056 2.249932)
			(stroke
				(width 0.1)
				(type default)
			)
			(layer "B.Fab")
		)
		(fp_line
			(start 3.750056 -2.249932)
			(end -3.750056 -2.249932)
			(stroke
				(width 0.1)
				(type default)
			)
			(layer "B.Fab")
		)
		(fp_text user "-"
			(at -4.543044 1.90627 270)
			(unlocked yes)
			(layer "B.SilkS")
			(effects
				(font
					(size 1.905 1.4224)
					(thickness 0.1524)
				)
				(justify left mirror)
			)
		)
		(fp_text user "+"
			(at 6.483604 0.760476 180)
			(unlocked yes)
			(layer "B.SilkS")
			(effects
				(font
					(size 1.905 1.4224)
					(thickness 0.1524)
				)
				(justify left mirror)
			)
		)
		(fp_text user "+"
			(at 6.322314 0.786384 180)
			(unlocked yes)
			(layer "B.Fab")
			(effects
				(font
					(size 1.905 1.4224)
					(thickness 0.1524)
				)
				(justify left mirror)
			)
		)
		(fp_text user "-"
			(at -4.8514 -0.14605 270)
			(unlocked yes)
			(layer "B.Fab")
			(effects
				(font
					(size 1.905 1.4224)
					(thickness 0.1524)
				)
				(justify left mirror)
			)
		)
		(pad "1" smd rect
			(at 3.199892 0 90)
			(size 2.413 2.8194)
			(layers "B.Cu" "B.Mask" "B.Paste")
			(net "PVDDIO_P1")
		)
		(pad "2" smd rect
			(at -3.199892 0 90)
			(size 2.413 2.8194)
			(layers "B.Cu" "B.Mask" "B.Paste")
			(net "GND")
		)
	)
	(footprint ""
		(layer "B.Cu")
		(at 365.846868 -423.022776 180)
		(property "Reference" "R838"
			(at 0 0 0)
			(layer "B.SilkS")
			(hide yes)
			(effects
				(font
					(size 1.27 1.27)
				)
				(justify mirror)
			)
		)
		(property "Value" ""
			(at 0 0 0)
			(layer "B.Fab")
			(effects
				(font
					(size 1.27 1.27)
				)
				(justify mirror)
			)
		)
		(duplicate_pad_numbers_are_jumpers no)
		(fp_line
			(start 0.32512 0.175006)
			(end 0.32512 -0.175006)
			(stroke
				(width 0.1)
				(type default)
			)
			(layer "B.Fab")
		)
		(fp_line
			(start 0.32512 -0.175006)
			(end -0.32512 -0.175006)
			(stroke
				(width 0.1)
				(type default)
			)
			(layer "B.Fab")
		)
		(fp_line
			(start -0.32512 0.175006)
			(end 0.32512 0.175006)
			(stroke
				(width 0.1)
				(type default)
			)
			(layer "B.Fab")
		)
		(fp_line
			(start -0.32512 -0.175006)
			(end -0.32512 0.175006)
			(stroke
				(width 0.1)
				(type default)
			)
			(layer "B.Fab")
		)
		(pad "1" smd rect
			(at 0.2667 0)
			(size 0.3048 0.381)
			(layers "B.Cu" "B.Mask" "B.Paste")
			(net "P1V8_CPU0_RT_1D")
		)
		(pad "2" smd rect
			(at -0.2667 0 180)
			(size 0.3048 0.381)
			(layers "B.Cu" "B.Mask" "B.Paste")
			(net "SMB_RT_CPU0_P3_ROM_R_SDA")
		)
	)
)
